# T6G (Grand Teton) — schematic netlist excerpt (pin names and nets, part order shuffled) for the footprints in the layout excerpt that follows; sources: Cadence DE-HDL packaged netlist, KiCad conversion of 04192023_DAF0TMB3IC0_F0TG_MB_C_brd_V02_OCP.brd

PC449_2  Q_CAP  22UF 16V 20% X6S  pkg C0805  page 222 : A = SW_P12V_AUX_PVDDIO_P1_FLT ; B = GND
C2289  Q_CAP  22UF 4V 20% X6S  pkg C0402  page 72 : A = PVDD11_S3_P1 ; B = GND
C2353  Q_CAP  22UF 4V 20% X6S  pkg C0402  page 73 : A = PVDDCR_CPU1_P1 ; B = GND

(kicad_pcb
	(version 20260206)
	(generator "pcbnew")
	(generator_version "10.0")
	(general
		(thickness 1.6)
		(legacy_teardrops no)
	)
	(paper "A4")
	(title_block
		(title "04192023_DAF0TMB3IC0_F0TG_MB_C_brd_V02_OCP.brd")
		(comment 1 "Grand Teton / footprints 6244-6246 of 8354")
	)
	(layers
		(0 "F.Cu" signal "TOP")
		(4 "In1.Cu" signal "GND")
		(6 "In2.Cu" signal "IN1")
		(8 "In3.Cu" signal "GND1")
		(10 "In4.Cu" signal "IN2")
		(12 "In5.Cu" signal "GND2")
		(14 "In6.Cu" signal "IN3")
		(16 "In7.Cu" signal "GND3")
		(18 "In8.Cu" signal "VCC")
		(20 "In9.Cu" signal "VCC1")
		(22 "In10.Cu" signal "GND4")
		(24 "In11.Cu" signal "IN4")
		(26 "In12.Cu" signal "GND5")
		(28 "In13.Cu" signal "IN5")
		(30 "In14.Cu" signal "GND6")
		(32 "In15.Cu" signal "IN6")
		(34 "In16.Cu" signal "GND7")
		(2 "B.Cu" signal "BOTTOM")
		(9 "F.Adhes" user "F.Adhesive")
		(11 "B.Adhes" user "B.Adhesive")
		(13 "F.Paste" user "Package Geometry/Pastemask Top")
		(15 "B.Paste" user "Package Geometry/Pastemask Bottom")
		(5 "F.SilkS" user "Ref Des/Silkscreen Top")
		(7 "B.SilkS" user "Ref Des/Silkscreen Bottom")
		(1 "F.Mask" user "Board Geometry/Soldermask Top")
		(3 "B.Mask" user "Board Geometry/Soldermask Bottom")
		(17 "Dwgs.User" user "User.Drawings")
		(19 "Cmts.User" user "User.Comments")
		(21 "Eco1.User" user "User.Eco1")
		(23 "Eco2.User" user "User.Eco2")
		(25 "Edge.Cuts" user "Board Geometry/Outline")
		(27 "Margin" user)
		(31 "F.CrtYd" user "Package Geometry/Place Bound Top")
		(29 "B.CrtYd" user "Package Geometry/Place Bound Bottom")
		(35 "F.Fab" user "Ref Des/Assembly Top")
		(33 "B.Fab" user "Ref Des/Assembly Bottom")
	)
	(footprint ""
		(layer "B.Cu")
		(at 108.371386 -266.005564)
		(property "Reference" "C2289"
			(at 0 0 0)
			(layer "B.SilkS")
			(hide yes)
			(effects
				(font
					(size 1.27 1.27)
				)
				(justify mirror)
			)
		)
		(property "Value" ""
			(at 0 0 0)
			(layer "B.Fab")
			(effects
				(font
					(size 1.27 1.27)
				)
				(justify mirror)
			)
		)
		(duplicate_pad_numbers_are_jumpers no)
		(fp_line
			(start -0.7874 -0.4064)
			(end -0.7874 0.4064)
			(stroke
				(width 0.1524)
				(type default)
			)
			(layer "B.SilkS")
		)
		(fp_line
			(start -0.7874 0.4064)
			(end 0.7874 0.4064)
			(stroke
				(width 0.1524)
				(type default)
			)
			(layer "B.SilkS")
		)
		(fp_line
			(start 0.7874 -0.4064)
			(end -0.7874 -0.4064)
			(stroke
				(width 0.1524)
				(type default)
			)
			(layer "B.SilkS")
		)
		(fp_line
			(start 0.7874 0.4064)
			(end 0.7874 -0.4064)
			(stroke
				(width 0.1524)
				(type default)
			)
			(layer "B.SilkS")
		)
		(fp_line
			(start -0.67945 -0.3048)
			(end -0.67945 0.3048)
			(stroke
				(width 0.1)
				(type default)
			)
			(layer "B.Fab")
		)
		(fp_line
			(start -0.67945 0.3048)
			(end -0.120396 0.3048)
			(stroke
				(width 0.1)
				(type default)
			)
			(layer "B.Fab")
		)
		(fp_line
			(start -0.12065 -0.3048)
			(end -0.67945 -0.3048)
			(stroke
				(width 0.1)
				(type default)
			)
			(layer "B.Fab")
		)
		(fp_line
			(start -0.12065 -0.2794)
			(end -0.12065 -0.3048)
			(stroke
				(width 0.1)
				(type default)
			)
			(layer "B.Fab")
		)
		(fp_line
			(start -0.120396 0.2794)
			(end 0.12065 0.2794)
			(stroke
				(width 0.1)
				(type default)
			)
			(layer "B.Fab")
		)
		(fp_line
			(start -0.120396 0.3048)
			(end -0.120396 0.2794)
			(stroke
				(width 0.1)
				(type default)
			)
			(layer "B.Fab")
		)
		(fp_line
			(start 0.12065 -0.305054)
			(end 0.12065 -0.2794)
			(stroke
				(width 0.1)
				(type default)
			)
			(layer "B.Fab")
		)
		(fp_line
			(start 0.12065 -0.2794)
			(end -0.12065 -0.2794)
			(stroke
				(width 0.1)
				(type default)
			)
			(layer "B.Fab")
		)
		(fp_line
			(start 0.12065 0.2794)
			(end 0.12065 0.3048)
			(stroke
				(width 0.1)
				(type default)
			)
			(layer "B.Fab")
		)
		(fp_line
			(start 0.12065 0.3048)
			(end 0.67945 0.3048)
			(stroke
				(width 0.1)
				(type default)
			)
			(layer "B.Fab")
		)
		(fp_line
			(start 0.67945 -0.305054)
			(end 0.12065 -0.305054)
			(stroke
				(width 0.1)
				(type default)
			)
			(layer "B.Fab")
		)
		(fp_line
			(start 0.67945 0.3048)
			(end 0.67945 -0.305054)
			(stroke
				(width 0.1)
				(type default)
			)
			(layer "B.Fab")
		)
		(pad "1" smd circle
			(at 0.40005 0 180)
			(size 0 0)
			(layers "B.Cu" "B.Mask" "B.Paste")
			(net "PVDD11_S3_P1")
		)
		(pad "2" smd circle
			(at -0.40005 0 180)
			(size 0 0)
			(layers "B.Cu" "B.Mask" "B.Paste")
			(net "GND")
		)
	)
	(footprint ""
		(layer "B.Cu")
		(at 121.579386 -269.307564 180)
		(property "Reference" "C2353"
			(at 0 0 0)
			(layer "B.SilkS")
			(hide yes)
			(effects
				(font
					(size 1.27 1.27)
				)
				(justify mirror)
			)
		)
		(property "Value" ""
			(at 0 0 0)
			(layer "B.Fab")
			(effects
				(font
					(size 1.27 1.27)
				)
				(justify mirror)
			)
		)
		(duplicate_pad_numbers_are_jumpers no)
		(fp_line
			(start 0.7874 0.4064)
			(end 0.7874 -0.4064)
			(stroke
				(width 0.1524)
				(type default)
			)
			(layer "B.SilkS")
		)
		(fp_line
			(start 0.7874 -0.4064)
			(end -0.7874 -0.4064)
			(stroke
				(width 0.1524)
				(type default)
			)
			(layer "B.SilkS")
		)
		(fp_line
			(start -0.7874 0.4064)
			(end 0.7874 0.4064)
			(stroke
				(width 0.1524)
				(type default)
			)
			(layer "B.SilkS")
		)
		(fp_line
			(start -0.7874 -0.4064)
			(end -0.7874 0.4064)
			(stroke
				(width 0.1524)
				(type default)
			)
			(layer "B.SilkS")
		)
		(fp_line
			(start 0.67945 0.3048)
			(end 0.67945 -0.305054)
			(stroke
				(width 0.1)
				(type default)
			)
			(layer "B.Fab")
		)
		(fp_line
			(start 0.67945 -0.305054)
			(end 0.12065 -0.305054)
			(stroke
				(width 0.1)
				(type default)
			)
			(layer "B.Fab")
		)
		(fp_line
			(start 0.12065 0.3048)
			(end 0.67945 0.3048)
			(stroke
				(width 0.1)
				(type default)
			)
			(layer "B.Fab")
		)
		(fp_line
			(start 0.12065 0.2794)
			(end 0.12065 0.3048)
			(stroke
				(width 0.1)
				(type default)
			)
			(layer "B.Fab")
		)
		(fp_line
			(start 0.12065 -0.2794)
			(end -0.12065 -0.2794)
			(stroke
				(width 0.1)
				(type default)
			)
			(layer "B.Fab")
		)
		(fp_line
			(start 0.12065 -0.305054)
			(end 0.12065 -0.2794)
			(stroke
				(width 0.1)
				(type default)
			)
			(layer "B.Fab")
		)
		(fp_line
			(start -0.120396 0.3048)
			(end -0.120396 0.2794)
			(stroke
				(width 0.1)
				(type default)
			)
			(layer "B.Fab")
		)
		(fp_line
			(start -0.120396 0.2794)
			(end 0.12065 0.2794)
			(stroke
				(width 0.1)
				(type default)
			)
			(layer "B.Fab")
		)
		(fp_line
			(start -0.12065 -0.2794)
			(end -0.12065 -0.3048)
			(stroke
				(width 0.1)
				(type default)
			)
			(layer "B.Fab")
		)
		(fp_line
			(start -0.12065 -0.3048)
			(end -0.67945 -0.3048)
			(stroke
				(width 0.1)
				(type default)
			)
			(layer "B.Fab")
		)
		(fp_line
			(start -0.67945 0.3048)
			(end -0.120396 0.3048)
			(stroke
				(width 0.1)
				(type default)
			)
			(layer "B.Fab")
		)
		(fp_line
			(start -0.67945 -0.3048)
			(end -0.67945 0.3048)
			(stroke
				(width 0.1)
				(type default)
			)
			(layer "B.Fab")
		)
		(pad "1" smd circle
			(at 0.40005 0)
			(size 0 0)
			(layers "B.Cu" "B.Mask" "B.Paste")
			(net "PVDDCR_CPU1_P1")
		)
		(pad "2" smd circle
			(at -0.40005 0)
			(size 0 0)
			(layers "B.Cu" "B.Mask" "B.Paste")
			(net "GND")
		)
	)
	(footprint ""
		(layer "B.Cu")
		(at 48.43653 -346.788994 90)
		(property "Reference" "PC449_2"
			(at 0 0 90)
			(layer "B.SilkS")
			(hide yes)
			(effects
				(font
					(size 1.27 1.27)
				)
				(justify mirror)
			)
		)
		(property "Value" ""
			(at 0 0 90)
			(layer "B.Fab")
			(effects
				(font
					(size 1.27 1.27)
				)
				(justify mirror)
			)
		)
		(duplicate_pad_numbers_are_jumpers no)
		(fp_line
			(start 1.524 -0.762)
			(end -1.524 -0.762)
			(stroke
				(width 0.1524)
				(type default)
			)
			(layer "B.SilkS")
		)
		(fp_line
			(start -1.524 -0.762)
			(end -1.524 0.762)
			(stroke
				(width 0.1524)
				(type default)
			)
			(layer "B.SilkS")
		)
		(fp_line
			(start 1.524 0.762)
			(end 1.524 -0.762)
			(stroke
				(width 0.1524)
				(type default)
			)
			(layer "B.SilkS")
		)
		(fp_line
			(start -1.524 0.762)
			(end 1.524 0.762)
			(stroke
				(width 0.1524)
				(type default)
			)
			(layer "B.SilkS")
		)
		(fp_line
			(start 1.1049 -0.724916)
			(end 1.1049 0.724916)
			(stroke
				(width 0.1)
				(type default)
			)
			(layer "B.Fab")
		)
		(fp_line
			(start -1.1049 -0.724916)
			(end 1.1049 -0.724916)
			(stroke
				(width 0.1)
				(type default)
			)
			(layer "B.Fab")
		)
		(fp_line
			(start 1.1049 0.724916)
			(end -1.1049 0.724916)
			(stroke
				(width 0.1)
				(type default)
			)
			(layer "B.Fab")
		)
		(fp_line
			(start -1.1049 0.724916)
			(end -1.1049 -0.724916)
			(stroke
				(width 0.1)
				(type default)
			)
			(layer "B.Fab")
		)
		(pad "1" smd rect
			(at 0.889 0 90)
			(size 1.016 1.27)
			(layers "B.Cu" "B.Mask" "B.Paste")
			(net "SW_P12V_AUX_PVDDIO_P1_FLT")
		)
		(pad "2" smd rect
			(at -0.889 0 90)
			(size 1.016 1.27)
			(layers "B.Cu" "B.Mask" "B.Paste")
			(net "GND")
		)
	)
)
